(kicad_pcb
	(version 20241229)
	(generator "pcbnew")
	(generator_version "9.0")
	(general
		(thickness 1.62)
		(legacy_teardrops no)
	)
	(paper "A3")
	(title_block
		(title "COM Express 7 Baseboard")
		(date "2025-02-04")
		(rev "1.1.2")
		(company "Antmicro Ltd")
		(comment 1 "www.antmicro.com")
		(comment 9 "footprints 474-477 of 802")
	)
	(layers
		(0 "F.Cu" signal)
		(4 "In1.Cu" signal)
		(6 "In2.Cu" signal)
		(8 "In3.Cu" signal)
		(10 "In4.Cu" signal)
		(12 "In5.Cu" signal)
		(14 "In6.Cu" signal)
		(2 "B.Cu" signal)
		(9 "F.Adhes" user "F.Adhesive")
		(11 "B.Adhes" user "B.Adhesive")
		(13 "F.Paste" user)
		(15 "B.Paste" user)
		(5 "F.SilkS" user "F.Silkscreen")
		(7 "B.SilkS" user "B.Silkscreen")
		(1 "F.Mask" user)
		(3 "B.Mask" user)
		(17 "Dwgs.User" user "User.Drawings")
		(19 "Cmts.User" user "User.Comments")
		(21 "Eco1.User" user "User.Eco1")
		(23 "Eco2.User" user "User.Eco2")
		(25 "Edge.Cuts" user)
		(27 "Margin" user)
		(31 "F.CrtYd" user "F.Courtyard")
		(29 "B.CrtYd" user "B.Courtyard")
		(35 "F.Fab" user)
		(33 "B.Fab" user)
	)
	(footprint "antmicro-footprints:C_0402_1005Metric"
		(layer "F.Cu")
		(at 193.902276 134.134199 135)
		(descr "Capacitor SMD 0402")
		(tags "capacitor SMD 0402")
		(property "Reference" "C136"
			(at 3.773458 -0.048138 135)
			(layer "F.SilkS")
			(effects
				(font
					(size 0.7 0.7)
					(thickness 0.15)
				)
				(justify left top)
			)
		)
		(property "Value" "C_100n_0402"
			(at -1.022927 2.155213 135)
			(layer "F.Fab")
			(effects
				(font
					(size 0.7 0.7)
					(thickness 0.15)
				)
				(justify left top)
			)
		)
		(property "Datasheet" "https://www.murata.com/products/productdetail?partno=GRM155R61H104KE14%23"
			(at 0 0 135)
			(layer "B.Fab")
			(hide yes)
			(effects
				(font
					(size 1.27 1.27)
					(thickness 0.15)
				)
				(justify mirror)
			)
		)
		(property "Author" "Antmicro"
			(at 322.014 53.288 45)
			(layer "F.Fab")
			(hide yes)
			(effects
				(font
					(size 1 1)
					(thickness 0.15)
				)
			)
		)
		(property "Dielectric" "X5R"
			(at 322.014 53.288 45)
			(layer "F.Fab")
			(hide yes)
			(effects
				(font
					(size 1 1)
					(thickness 0.15)
				)
			)
		)
		(property "License" "Apache-2.0"
			(at 322.014 53.288 45)
			(layer "F.Fab")
			(hide yes)
			(effects
				(font
					(size 1 1)
					(thickness 0.15)
				)
			)
		)
		(property "MPN" "GRM155R61H104KE14D"
			(at 322.014 53.288 45)
			(layer "F.Fab")
			(hide yes)
			(effects
				(font
					(size 1 1)
					(thickness 0.15)
				)
			)
		)
		(property "Manufacturer" "Murata"
			(at 322.014 53.288 45)
			(layer "F.Fab")
			(hide yes)
			(effects
				(font
					(size 1 1)
					(thickness 0.15)
				)
			)
		)
		(property "Public" "False"
			(at 322.014 53.288 45)
			(layer "F.Fab")
			(hide yes)
			(effects
				(font
					(size 1 1)
					(thickness 0.15)
				)
			)
		)
		(property "Val" "100n"
			(at 322.014 53.288 45)
			(layer "F.Fab")
			(hide yes)
			(effects
				(font
					(size 1 1)
					(thickness 0.15)
				)
			)
		)
		(property "Voltage" "50V"
			(at 322.014 53.288 45)
			(layer "F.Fab")
			(hide yes)
			(effects
				(font
					(size 1 1)
					(thickness 0.15)
				)
			)
		)
		(sheetname "PCIe redriver")
		(sheetfile "pcie_redriver.kicad_sch")
		(attr smd)
		(fp_poly
			(pts
				(xy -0.925 -0.47) (xy 0.925 -0.47) (xy 0.925 0.47) (xy -0.925 0.47)
			)
			(stroke
				(width 0.05)
				(type default)
			)
			(fill no)
			(layer "F.CrtYd")
		)
		(fp_line
			(start 0.504 -0.25)
			(end 0.504 0.248)
			(stroke
				(width 0.15)
				(type solid)
			)
			(layer "F.Fab")
		)
		(fp_line
			(start 0.504 0.248)
			(end -0.494 0.248)
			(stroke
				(width 0.15)
				(type solid)
			)
			(layer "F.Fab")
		)
		(fp_line
			(start -0.494 -0.25)
			(end 0.504 -0.25)
			(stroke
				(width 0.15)
				(type solid)
			)
			(layer "F.Fab")
		)
		(fp_line
			(start -0.494 0.248)
			(end -0.494 -0.25)
			(stroke
				(width 0.15)
				(type solid)
			)
			(layer "F.Fab")
		)
		(pad "1" smd roundrect
			(at -0.48 0 135)
			(size 0.59 0.64)
			(layers "F.Cu" "F.Mask" "F.Paste")
			(roundrect_rratio 0.25)
			(net 1 "GND")
			(pintype "passive")
			(teardrops
				(best_length_ratio 0.2)
				(max_length 1)
				(best_width_ratio 0.9)
				(max_width 2)
				(curved_edges yes)
				(filter_ratio 0.9)
				(enabled yes)
				(allow_two_segments yes)
				(prefer_zone_connections yes)
			)
		)
		(pad "2" smd roundrect
			(at 0.48 0 135)
			(size 0.59 0.64)
			(layers "F.Cu" "F.Mask" "F.Paste")
			(roundrect_rratio 0.25)
			(net 2 "+3V3")
			(pintype "passive")
			(teardrops
				(best_length_ratio 0.2)
				(max_length 1)
				(best_width_ratio 0.9)
				(max_width 2)
				(curved_edges yes)
				(filter_ratio 0.9)
				(enabled yes)
				(allow_two_segments yes)
				(prefer_zone_connections yes)
			)
		)
	)
	(footprint "antmicro-footprints:C_0402_1005Metric"
		(layer "F.Cu")
		(at 194.962937 133.073539 135)
		(descr "Capacitor SMD 0402")
		(tags "capacitor SMD 0402")
		(property "Reference" "C138"
			(at 3.773458 -0.558189 135)
			(layer "F.SilkS")
			(effects
				(font
					(size 0.7 0.7)
					(thickness 0.15)
				)
				(justify left top)
			)
		)
		(property "Value" "C_100n_0402"
			(at -1.022927 2.155213 135)
			(layer "F.Fab")
			(effects
				(font
					(size 0.7 0.7)
					(thickness 0.15)
				)
				(justify left top)
			)
		)
		(property "Datasheet" "https://www.murata.com/products/productdetail?partno=GRM155R61H104KE14%23"
			(at 0 0 135)
			(layer "B.Fab")
			(hide yes)
			(effects
				(font
					(size 1.27 1.27)
					(thickness 0.15)
				)
				(justify mirror)
			)
		)
		(property "Author" "Antmicro"
			(at 320.514 51.788 45)
			(layer "F.Fab")
			(hide yes)
			(effects
				(font
					(size 1 1)
					(thickness 0.15)
				)
			)
		)
		(property "Dielectric" "X5R"
			(at 320.514 51.788 45)
			(layer "F.Fab")
			(hide yes)
			(effects
				(font
					(size 1 1)
					(thickness 0.15)
				)
			)
		)
		(property "License" "Apache-2.0"
			(at 320.514 51.788 45)
			(layer "F.Fab")
			(hide yes)
			(effects
				(font
					(size 1 1)
					(thickness 0.15)
				)
			)
		)
		(property "MPN" "GRM155R61H104KE14D"
			(at 320.514 51.788 45)
			(layer "F.Fab")
			(hide yes)
			(effects
				(font
					(size 1 1)
					(thickness 0.15)
				)
			)
		)
		(property "Manufacturer" "Murata"
			(at 320.514 51.788 45)
			(layer "F.Fab")
			(hide yes)
			(effects
				(font
					(size 1 1)
					(thickness 0.15)
				)
			)
		)
		(property "Public" "False"
			(at 320.514 51.788 45)
			(layer "F.Fab")
			(hide yes)
			(effects
				(font
					(size 1 1)
					(thickness 0.15)
				)
			)
		)
		(property "Val" "100n"
			(at 320.514 51.788 45)
			(layer "F.Fab")
			(hide yes)
			(effects
				(font
					(size 1 1)
					(thickness 0.15)
				)
			)
		)
		(property "Voltage" "50V"
			(at 320.514 51.788 45)
			(layer "F.Fab")
			(hide yes)
			(effects
				(font
					(size 1 1)
					(thickness 0.15)
				)
			)
		)
		(sheetname "PCIe redriver")
		(sheetfile "pcie_redriver.kicad_sch")
		(attr smd)
		(fp_poly
			(pts
				(xy -0.925 -0.47) (xy 0.925 -0.47) (xy 0.925 0.47) (xy -0.925 0.47)
			)
			(stroke
				(width 0.05)
				(type default)
			)
			(fill no)
			(layer "F.CrtYd")
		)
		(fp_line
			(start 0.504 -0.25)
			(end 0.504 0.248)
			(stroke
				(width 0.15)
				(type solid)
			)
			(layer "F.Fab")
		)
		(fp_line
			(start 0.504 0.248)
			(end -0.494 0.248)
			(stroke
				(width 0.15)
				(type solid)
			)
			(layer "F.Fab")
		)
		(fp_line
			(start -0.494 -0.25)
			(end 0.504 -0.25)
			(stroke
				(width 0.15)
				(type solid)
			)
			(layer "F.Fab")
		)
		(fp_line
			(start -0.494 0.248)
			(end -0.494 -0.25)
			(stroke
				(width 0.15)
				(type solid)
			)
			(layer "F.Fab")
		)
		(pad "1" smd roundrect
			(at -0.48 0 135)
			(size 0.59 0.64)
			(layers "F.Cu" "F.Mask" "F.Paste")
			(roundrect_rratio 0.25)
			(net 1 "GND")
			(pintype "passive")
			(teardrops
				(best_length_ratio 0.2)
				(max_length 1)
				(best_width_ratio 0.9)
				(max_width 2)
				(curved_edges yes)
				(filter_ratio 0.9)
				(enabled yes)
				(allow_two_segments yes)
				(prefer_zone_connections yes)
			)
		)
		(pad "2" smd roundrect
			(at 0.48 0 135)
			(size 0.59 0.64)
			(layers "F.Cu" "F.Mask" "F.Paste")
			(roundrect_rratio 0.25)
			(net 2 "+3V3")
			(pintype "passive")
			(teardrops
				(best_length_ratio 0.2)
				(max_length 1)
				(best_width_ratio 0.9)
				(max_width 2)
				(curved_edges yes)
				(filter_ratio 0.9)
				(enabled yes)
				(allow_two_segments yes)
				(prefer_zone_connections yes)
			)
		)
	)
	(footprint "antmicro-footprints:C_0402_1005Metric"
		(layer "F.Cu")
		(at 231.270707 78.115 -90)
		(descr "Capacitor SMD 0402")
		(tags "capacitor SMD 0402")
		(property "Reference" "C88"
			(at -1.105 0.499999 90)
			(layer "F.SilkS")
			(effects
				(font
					(size 0.7 0.7)
					(thickness 0.15)
				)
				(justify right bottom)
			)
		)
		(property "Value" "C_100n_0402"
			(at -1.022927 2.155213 90)
			(layer "F.Fab")
			(effects
				(font
					(size 0.7 0.7)
					(thickness 0.15)
				)
				(justify right bottom)
			)
		)
		(property "Datasheet" "https://www.murata.com/products/productdetail?partno=GRM155R61H104KE14%23"
			(at 0 0 270)
			(layer "F.Fab")
			(hide yes)
			(effects
				(font
					(size 1.27 1.27)
					(thickness 0.15)
				)
			)
		)
		(property "Author" "Antmicro"
			(at 153.155707 309.385707 0)
			(layer "F.Fab")
			(hide yes)
			(effects
				(font
					(size 1 1)
					(thickness 0.15)
				)
			)
		)
		(property "Dielectric" "X5R"
			(at 153.155707 309.385707 0)
			(layer "F.Fab")
			(hide yes)
			(effects
				(font
					(size 1 1)
					(thickness 0.15)
				)
			)
		)
		(property "License" "Apache-2.0"
			(at 153.155707 309.385707 0)
			(layer "F.Fab")
			(hide yes)
			(effects
				(font
					(size 1 1)
					(thickness 0.15)
				)
			)
		)
		(property "MPN" "GRM155R61H104KE14D"
			(at 153.155707 309.385707 0)
			(layer "F.Fab")
			(hide yes)
			(effects
				(font
					(size 1 1)
					(thickness 0.15)
				)
			)
		)
		(property "Manufacturer" "Murata"
			(at 153.155707 309.385707 0)
			(layer "F.Fab")
			(hide yes)
			(effects
				(font
					(size 1 1)
					(thickness 0.15)
				)
			)
		)
		(property "Public" "False"
			(at 153.155707 309.385707 0)
			(layer "F.Fab")
			(hide yes)
			(effects
				(font
					(size 1 1)
					(thickness 0.15)
				)
			)
		)
		(property "Val" "100n"
			(at 153.155707 309.385707 0)
			(layer "F.Fab")
			(hide yes)
			(effects
				(font
					(size 1 1)
					(thickness 0.15)
				)
			)
		)
		(property "Voltage" "50V"
			(at 153.155707 309.385707 0)
			(layer "F.Fab")
			(hide yes)
			(effects
				(font
					(size 1 1)
					(thickness 0.15)
				)
			)
		)
		(sheetname "Misc")
		(sheetfile "misc.kicad_sch")
		(attr smd)
		(fp_rect
			(start -0.925 -0.47)
			(end 0.925 0.47)
			(stroke
				(width 0.05)
				(type default)
			)
			(fill no)
			(layer "F.CrtYd")
		)
		(fp_line
			(start -0.494 0.248)
			(end -0.494 -0.25)
			(stroke
				(width 0.15)
				(type solid)
			)
			(layer "F.Fab")
		)
		(fp_line
			(start 0.504 0.248)
			(end -0.494 0.248)
			(stroke
				(width 0.15)
				(type solid)
			)
			(layer "F.Fab")
		)
		(fp_line
			(start -0.494 -0.25)
			(end 0.504 -0.25)
			(stroke
				(width 0.15)
				(type solid)
			)
			(layer "F.Fab")
		)
		(fp_line
			(start 0.504 -0.25)
			(end 0.504 0.248)
			(stroke
				(width 0.15)
				(type solid)
			)
			(layer "F.Fab")
		)
		(pad "1" smd roundrect
			(at -0.48 0 270)
			(size 0.59 0.64)
			(layers "F.Cu" "F.Mask" "F.Paste")
			(roundrect_rratio 0.25)
			(net 1 "GND")
			(pintype "passive")
			(teardrops
				(best_length_ratio 0.2)
				(max_length 1)
				(best_width_ratio 0.9)
				(max_width 2)
				(curved_edges yes)
				(filter_ratio 0.9)
				(enabled yes)
				(allow_two_segments yes)
				(prefer_zone_connections yes)
			)
		)
		(pad "2" smd roundrect
			(at 0.48 0 270)
			(size 0.59 0.64)
			(layers "F.Cu" "F.Mask" "F.Paste")
			(roundrect_rratio 0.25)
			(net 2 "+3V3")
			(pintype "passive")
			(teardrops
				(best_length_ratio 0.2)
				(max_length 1)
				(best_width_ratio 0.9)
				(max_width 2)
				(curved_edges yes)
				(filter_ratio 0.9)
				(enabled yes)
				(allow_two_segments yes)
				(prefer_zone_connections yes)
			)
		)
	)
	(footprint "antmicro-footprints:Vishay_PowerPAK_1212-8_Single"
		(layer "F.Cu")
		(at 293.1 99.01 -90)
		(descr "PowerPAK 1212-8 Single")
		(tags "Vishay PowerPAK 1212-8 Single")
		(property "Reference" "Q4"
			(at -2.15 -1.95 0)
			(layer "F.SilkS")
			(effects
				(font
					(size 0.7 0.7)
					(thickness 0.15)
				)
				(justify right bottom)
			)
		)
		(property "Value" "SI7613DN-T1-GE3"
			(at 0 2.7 90)
			(layer "F.Fab")
			(effects
				(font
					(size 0.7 0.7)
					(thickness 0.15)
				)
				(justify right bottom)
			)
		)
		(property "Datasheet" "https://www.vishay.com/docs/64809/si7613dn.pdf"
			(at 0 0 270)
			(layer "F.Fab")
			(hide yes)
			(effects
				(font
					(size 1.27 1.27)
					(thickness 0.15)
				)
			)
		)
		(property "Author" "Antmicro"
			(at 194.09 392.11 0)
			(layer "F.Fab")
			(hide yes)
			(effects
				(font
					(size 1 1)
					(thickness 0.15)
				)
			)
		)
		(property "License" "Apache-2.0"
			(at 194.09 392.11 0)
			(layer "F.Fab")
			(hide yes)
			(effects
				(font
					(size 1 1)
					(thickness 0.15)
				)
			)
		)
		(property "MPN" "SI7613DN-T1-GE3"
			(at 194.09 392.11 0)
			(layer "F.Fab")
			(hide yes)
			(effects
				(font
					(size 1 1)
					(thickness 0.15)
				)
			)
		)
		(property "Manufacturer" "Vishay"
			(at 194.09 392.11 0)
			(layer "F.Fab")
			(hide yes)
			(effects
				(font
					(size 1 1)
					(thickness 0.15)
				)
			)
		)
		(sheetname "Power")
		(sheetfile "power.kicad_sch")
		(attr smd)
		(fp_line
			(start -1.635 1.634)
			(end 1.634 1.634)
			(stroke
				(width 0.15)
				(type solid)
			)
			(layer "F.SilkS")
		)
		(fp_line
			(start -1.635 1.3)
			(end -1.635 1.634)
			(stroke
				(width 0.15)
				(type solid)
			)
			(layer "F.SilkS")
		)
		(fp_line
			(start 1.634 1.3)
			(end 1.634 1.634)
			(stroke
				(width 0.15)
				(type solid)
			)
			(layer "F.SilkS")
		)
		(fp_line
			(start -1.651 -1.651)
			(end -1.651 -1.317)
			(stroke
				(width 0.15)
				(type solid)
			)
			(layer "F.SilkS")
		)
		(fp_line
			(start -1.651 -1.651)
			(end 1.648 -1.651)
			(stroke
				(width 0.15)
				(type solid)
			)
			(layer "F.SilkS")
		)
		(fp_line
			(start 1.648 -1.651)
			(end 1.648 -1.317)
			(stroke
				(width 0.15)
				(type solid)
			)
			(layer "F.SilkS")
		)
		(fp_circle
			(center -1.9 -1.4)
			(end -1.85 -1.4)
			(stroke
				(width 0.15)
				(type solid)
			)
			(fill yes)
			(layer "F.SilkS")
		)
		(fp_rect
			(start -2 -1.8)
			(end 2 1.798)
			(stroke
				(width 0.05)
				(type solid)
			)
			(fill no)
			(layer "F.CrtYd")
		)
		(fp_line
			(start -1.6425 -1.4175)
			(end -1.4175 -1.6425)
			(stroke
				(width 0.15)
				(type solid)
			)
			(layer "F.Fab")
		)
		(fp_rect
			(start -1.651 -1.651)
			(end 1.648 1.648)
			(stroke
				(width 0.15)
				(type solid)
			)
			(fill no)
			(layer "F.Fab")
		)
		(pad "1" smd rect
			(at -1.436 -0.99 270)
			(size 0.99 0.405)
			(layers "F.Cu" "F.Mask" "F.Paste")
			(net 77 "+5V_AON")
			(pinfunction "S")
			(pintype "passive")
			(teardrops
				(best_length_ratio 0.2)
				(max_length 1)
				(best_width_ratio 0.9)
				(max_width 2)
				(curved_edges yes)
				(filter_ratio 0.9)
				(enabled yes)
				(allow_two_segments yes)
				(prefer_zone_connections yes)
			)
		)
		(pad "2" smd rect
			(at -1.436 -0.332 270)
			(size 0.99 0.405)
			(layers "F.Cu" "F.Mask" "F.Paste")
			(net 77 "+5V_AON")
			(pinfunction "S")
			(pintype "passive")
			(teardrops
				(best_length_ratio 0.2)
				(max_length 1)
				(best_width_ratio 0.9)
				(max_width 2)
				(curved_edges yes)
				(filter_ratio 0.9)
				(enabled yes)
				(allow_two_segments yes)
				(prefer_zone_connections yes)
			)
		)
		(pad "3" smd rect
			(at -1.436 0.33 270)
			(size 0.99 0.405)
			(layers "F.Cu" "F.Mask" "F.Paste")
			(net 77 "+5V_AON")
			(pinfunction "S")
			(pintype "passive")
			(teardrops
				(best_length_ratio 0.2)
				(max_length 1)
				(best_width_ratio 0.9)
				(max_width 2)
				(curved_edges yes)
				(filter_ratio 0.9)
				(enabled yes)
				(allow_two_segments yes)
				(prefer_zone_connections yes)
			)
		)
		(pad "4" smd rect
			(at -1.436 0.988 270)
			(size 0.99 0.405)
			(layers "F.Cu" "F.Mask" "F.Paste")
			(net 536 "Net-(Q3-D)")
			(pinfunction "G")
			(pintype "passive")
			(teardrops
				(best_length_ratio 0.2)
				(max_length 1)
				(best_width_ratio 0.9)
				(max_width 2)
				(curved_edges yes)
				(filter_ratio 0.9)
				(enabled yes)
				(allow_two_segments yes)
				(prefer_zone_connections yes)
			)
		)
		(pad "5" smd custom
			(at 0.557 0 270)
			(size 1.725 2.235)
			(layers "F.Cu" "F.Mask" "F.Paste")
			(net 52 "+5V")
			(pinfunction "D")
			(pintype "passive")
			(zone_connect 2)
			(options
				(clearance outline)
				(anchor rect)
			)
			(primitives
				(gr_poly
					(pts
						(xy 0.8625 0.1275) (xy 0.8625 -0.1275) (xy 1.3725 -0.1275) (xy 1.3725 -0.5325) (xy 0.8625 -0.5325)
						(xy 0.8625 -0.7875) (xy 1.3725 -0.7875) (xy 1.3725 -1.195) (xy 0.6125 -1.195) (xy 0.6125 1.195)
						(xy 1.3725 1.195) (xy 1.3725 0.7875) (xy 0.8625 0.7875) (xy 0.8625 0.5325) (xy 1.3725 0.5325)
						(xy 1.3725 0.1275)
					)
					(width 0)
					(fill yes)
				)
			)
			(teardrops
				(best_length_ratio 0.2)
				(max_length 1)
				(best_width_ratio 0.9)
				(max_width 2)
				(curved_edges yes)
				(filter_ratio 0.9)
				(enabled yes)
				(allow_two_segments yes)
				(prefer_zone_connections yes)
			)
		)
	)
)
